(kicad_pcb
	(version 20241229)
	(generator "pcbnew")
	(generator_version "9.0")
	(general
		(thickness 1.62)
		(legacy_teardrops no)
	)
	(paper "A3")
	(title_block
		(title "COM Express 7 Baseboard")
		(date "2025-02-04")
		(rev "1.1.2")
		(company "Antmicro Ltd")
		(comment 1 "www.antmicro.com")
		(comment 9 "footprints 275-276 of 802")
	)
	(layers
		(0 "F.Cu" signal)
		(4 "In1.Cu" signal)
		(6 "In2.Cu" signal)
		(8 "In3.Cu" signal)
		(10 "In4.Cu" signal)
		(12 "In5.Cu" signal)
		(14 "In6.Cu" signal)
		(2 "B.Cu" signal)
		(9 "F.Adhes" user "F.Adhesive")
		(11 "B.Adhes" user "B.Adhesive")
		(13 "F.Paste" user)
		(15 "B.Paste" user)
		(5 "F.SilkS" user "F.Silkscreen")
		(7 "B.SilkS" user "B.Silkscreen")
		(1 "F.Mask" user)
		(3 "B.Mask" user)
		(17 "Dwgs.User" user "User.Drawings")
		(19 "Cmts.User" user "User.Comments")
		(21 "Eco1.User" user "User.Eco1")
		(23 "Eco2.User" user "User.Eco2")
		(25 "Edge.Cuts" user)
		(27 "Margin" user)
		(31 "F.CrtYd" user "F.Courtyard")
		(29 "B.CrtYd" user "B.Courtyard")
		(35 "F.Fab" user)
		(33 "B.Fab" user)
	)
	(footprint "antmicro-footprints:QFN-20-1EP_3x3mm_P0.45mm_TPS56xxxx"
		(layer "F.Cu")
		(at 311.714999 104.748999 180)
		(property "Reference" "U19"
			(at -1.885001 1.838999 0)
			(layer "F.SilkS")
			(effects
				(font
					(size 0.7 0.7)
					(thickness 0.15)
				)
				(justify right bottom)
			)
		)
		(property "Value" "TPS56C230"
			(at 0 2.898 0)
			(layer "F.Fab")
			(effects
				(font
					(size 0.7 0.7)
					(thickness 0.15)
				)
				(justify right bottom)
			)
		)
		(property "Datasheet" "https://www.ti.com/lit/ds/symlink/tps56c230.pdf?ts=1672843259715&ref_url=https%253A%252F%252Fwww.ti.com%252Fproduct%252FTPS56C230"
			(at 0 0 180)
			(layer "F.Fab")
			(hide yes)
			(effects
				(font
					(size 1.27 1.27)
					(thickness 0.15)
				)
			)
		)
		(property "Author" "Antmicro"
			(at 623.429998 209.497998 0)
			(layer "F.Fab")
			(hide yes)
			(effects
				(font
					(size 1 1)
					(thickness 0.15)
				)
			)
		)
		(property "License" "Apache-2.0"
			(at 623.429998 209.497998 0)
			(layer "F.Fab")
			(hide yes)
			(effects
				(font
					(size 1 1)
					(thickness 0.15)
				)
			)
		)
		(property "MPN" "TPS56C230RJER"
			(at 623.429998 209.497998 0)
			(layer "F.Fab")
			(hide yes)
			(effects
				(font
					(size 1 1)
					(thickness 0.15)
				)
			)
		)
		(property "Manufacturer" "Texas Instruments"
			(at 623.429998 209.497998 0)
			(layer "F.Fab")
			(hide yes)
			(effects
				(font
					(size 1 1)
					(thickness 0.15)
				)
			)
		)
		(sheetname "Power")
		(sheetfile "power.kicad_sch")
		(attr smd)
		(fp_line
			(start 1.5 -1.5)
			(end 1.5 -1.2)
			(stroke
				(width 0.15)
				(type solid)
			)
			(layer "F.SilkS")
		)
		(fp_line
			(start 1.499 1.5)
			(end 1.499 1.202)
			(stroke
				(width 0.15)
				(type solid)
			)
			(layer "F.SilkS")
		)
		(fp_line
			(start 1.202 -1.5)
			(end 1.5 -1.5)
			(stroke
				(width 0.15)
				(type solid)
			)
			(layer "F.SilkS")
		)
		(fp_line
			(start 1.201 1.5)
			(end 1.499 1.5)
			(stroke
				(width 0.15)
				(type solid)
			)
			(layer "F.SilkS")
		)
		(fp_line
			(start -1.2 1.498)
			(end -1.5 1.498)
			(stroke
				(width 0.15)
				(type solid)
			)
			(layer "F.SilkS")
		)
		(fp_line
			(start -1.5 1.498)
			(end -1.5 1.2)
			(stroke
				(width 0.15)
				(type solid)
			)
			(layer "F.SilkS")
		)
		(fp_line
			(start -1.5 -1.201)
			(end -1.5 -1.499)
			(stroke
				(width 0.15)
				(type solid)
			)
			(layer "F.SilkS")
		)
		(fp_line
			(start -1.5 -1.499)
			(end -1.2 -1.499)
			(stroke
				(width 0.15)
				(type solid)
			)
			(layer "F.SilkS")
		)
		(fp_circle
			(center -1.8 -1.15)
			(end -1.75 -1.15)
			(stroke
				(width 0.15)
				(type solid)
			)
			(fill yes)
			(layer "F.SilkS")
		)
		(fp_rect
			(start -1.8 -1.8)
			(end 1.8 1.8)
			(stroke
				(width 0.05)
				(type solid)
			)
			(fill no)
			(layer "F.CrtYd")
		)
		(fp_line
			(start 1.499 1.499)
			(end 1.499 -1.5)
			(stroke
				(width 0.15)
				(type solid)
			)
			(layer "F.Fab")
		)
		(fp_line
			(start 1.499 -1.5)
			(end -0.5 -1.5)
			(stroke
				(width 0.15)
				(type solid)
			)
			(layer "F.Fab")
		)
		(fp_line
			(start -0.5 -1.5)
			(end -1.5 -0.5)
			(stroke
				(width 0.15)
				(type solid)
			)
			(layer "F.Fab")
		)
		(fp_line
			(start -1.5 1.499)
			(end 1.499 1.499)
			(stroke
				(width 0.15)
				(type solid)
			)
			(layer "F.Fab")
		)
		(fp_line
			(start -1.5 -0.5)
			(end -1.5 1.499)
			(stroke
				(width 0.15)
				(type solid)
			)
			(layer "F.Fab")
		)
		(pad "1" smd oval
			(at -1.4 -0.905 270)
			(size 0.2 0.6)
			(layers "F.Cu" "F.Mask" "F.Paste")
			(net 68 "Net-(U19-BST)")
			(pinfunction "BST")
			(pintype "passive")
			(teardrops
				(best_length_ratio 0.2)
				(max_length 1)
				(best_width_ratio 0.9)
				(max_width 2)
				(curved_edges yes)
				(filter_ratio 0.9)
				(enabled yes)
				(allow_two_segments yes)
				(prefer_zone_connections yes)
			)
		)
		(pad "2" smd oval
			(at -1.4 -0.455 270)
			(size 0.2 0.6)
			(layers "F.Cu" "F.Mask" "F.Paste")
			(net 62 "+12V_AON")
			(pinfunction "V_{IN}")
			(pintype "power_in")
			(teardrops
				(best_length_ratio 0.2)
				(max_length 1)
				(best_width_ratio 0.9)
				(max_width 2)
				(curved_edges yes)
				(filter_ratio 0.9)
				(enabled yes)
				(allow_two_segments yes)
				(prefer_zone_connections yes)
			)
		)
		(pad "3" smd oval
			(at -1.4 0 270)
			(size 0.2 0.6)
			(layers "F.Cu" "F.Mask" "F.Paste")
			(net 62 "+12V_AON")
			(pinfunction "V_{IN}")
			(pintype "passive")
			(teardrops
				(best_length_ratio 0.2)
				(max_length 1)
				(best_width_ratio 0.9)
				(max_width 2)
				(curved_edges yes)
				(filter_ratio 0.9)
				(enabled yes)
				(allow_two_segments yes)
				(prefer_zone_connections yes)
			)
		)
		(pad "4" smd oval
			(at -1.4 0.45 270)
			(size 0.2 0.6)
			(layers "F.Cu" "F.Mask" "F.Paste")
			(net 62 "+12V_AON")
			(pinfunction "V_{IN}")
			(pintype "passive")
			(teardrops
				(best_length_ratio 0.2)
				(max_length 1)
				(best_width_ratio 0.9)
				(max_width 2)
				(curved_edges yes)
				(filter_ratio 0.9)
				(enabled yes)
				(allow_two_segments yes)
				(prefer_zone_connections yes)
			)
		)
		(pad "5" smd oval
			(at -1.4 0.9 270)
			(size 0.2 0.6)
			(layers "F.Cu" "F.Mask" "F.Paste")
			(net 62 "+12V_AON")
			(pinfunction "V_{IN}")
			(pintype "passive")
			(teardrops
				(best_length_ratio 0.2)
				(max_length 1)
				(best_width_ratio 0.9)
				(max_width 2)
				(curved_edges yes)
				(filter_ratio 0.9)
				(enabled yes)
				(allow_two_segments yes)
				(prefer_zone_connections yes)
			)
		)
		(pad "6" smd oval
			(at -0.905 1.4 180)
			(size 0.2 0.6)
			(layers "F.Cu" "F.Mask" "F.Paste")
			(net 69 "Net-(C48-Pad2)")
			(pinfunction "SW")
			(pintype "passive")
			(teardrops
				(best_length_ratio 0.2)
				(max_length 1)
				(best_width_ratio 0.9)
				(max_width 2)
				(curved_edges yes)
				(filter_ratio 0.9)
				(enabled yes)
				(allow_two_segments yes)
				(prefer_zone_connections yes)
			)
		)
		(pad "7" smd oval
			(at -0.455 1.4 180)
			(size 0.2 0.6)
			(layers "F.Cu" "F.Mask" "F.Paste")
			(net 1 "GND")
			(pinfunction "PGND")
			(pintype "passive")
			(teardrops
				(best_length_ratio 0.2)
				(max_length 1)
				(best_width_ratio 0.9)
				(max_width 2)
				(curved_edges yes)
				(filter_ratio 0.9)
				(enabled yes)
				(allow_two_segments yes)
				(prefer_zone_connections yes)
			)
		)
		(pad "8" smd oval
			(at 0 1.4 180)
			(size 0.2 0.6)
			(layers "F.Cu" "F.Mask" "F.Paste")
			(net 1 "GND")
			(pinfunction "PGND")
			(pintype "passive")
			(teardrops
				(best_length_ratio 0.2)
				(max_length 1)
				(best_width_ratio 0.9)
				(max_width 2)
				(curved_edges yes)
				(filter_ratio 0.9)
				(enabled yes)
				(allow_two_segments yes)
				(prefer_zone_connections yes)
			)
		)
		(pad "9" smd oval
			(at 0.45 1.4 180)
			(size 0.2 0.6)
			(layers "F.Cu" "F.Mask" "F.Paste")
			(net 889 "/Power/PG_{3V3}")
			(pinfunction "PG")
			(pintype "passive")
			(teardrops
				(best_length_ratio 0.2)
				(max_length 1)
				(best_width_ratio 0.9)
				(max_width 2)
				(curved_edges yes)
				(filter_ratio 0.9)
				(enabled yes)
				(allow_two_segments yes)
				(prefer_zone_connections yes)
			)
		)
		(pad "10" smd oval
			(at 0.9 1.4 180)
			(size 0.2 0.6)
			(layers "F.Cu" "F.Mask" "F.Paste")
			(net 776 "unconnected-(U19-NC-Pad10)")
			(pinfunction "NC")
			(pintype "no_connect")
			(teardrops
				(best_length_ratio 0.2)
				(max_length 1)
				(best_width_ratio 0.9)
				(max_width 2)
				(curved_edges yes)
				(filter_ratio 0.9)
				(enabled yes)
				(allow_two_segments yes)
				(prefer_zone_connections yes)
			)
		)
		(pad "11" smd oval
			(at 1.4 0.9 270)
			(size 0.2 0.6)
			(layers "F.Cu" "F.Mask" "F.Paste")
			(net 777 "unconnected-(U19-SS-Pad11)")
			(pinfunction "SS")
			(pintype "passive+no_connect")
			(teardrops
				(best_length_ratio 0.2)
				(max_length 1)
				(best_width_ratio 0.9)
				(max_width 2)
				(curved_edges yes)
				(filter_ratio 0.9)
				(enabled yes)
				(allow_two_segments yes)
				(prefer_zone_connections yes)
			)
		)
		(pad "12" smd oval
			(at 1.4 0.45 270)
			(size 0.2 0.6)
			(layers "F.Cu" "F.Mask" "F.Paste")
			(net 574 "Net-(U19-EN)")
			(pinfunction "EN")
			(pintype "passive")
			(teardrops
				(best_length_ratio 0.2)
				(max_length 1)
				(best_width_ratio 0.9)
				(max_width 2)
				(curved_edges yes)
				(filter_ratio 0.9)
				(enabled yes)
				(allow_two_segments yes)
				(prefer_zone_connections yes)
			)
		)
		(pad "13" smd oval
			(at 1.4 0 270)
			(size 0.2 0.6)
			(layers "F.Cu" "F.Mask" "F.Paste")
			(net 1 "GND")
			(pinfunction "AGND")
			(pintype "passive")
			(teardrops
				(best_length_ratio 0.2)
				(max_length 1)
				(best_width_ratio 0.9)
				(max_width 2)
				(curved_edges yes)
				(filter_ratio 0.9)
				(enabled yes)
				(allow_two_segments yes)
				(prefer_zone_connections yes)
			)
		)
		(pad "14" smd oval
			(at 1.4 -0.455 270)
			(size 0.2 0.6)
			(layers "F.Cu" "F.Mask" "F.Paste")
			(net 581 "Net-(U19-FB)")
			(pinfunction "FB")
			(pintype "passive")
			(teardrops
				(best_length_ratio 0.2)
				(max_length 1)
				(best_width_ratio 0.9)
				(max_width 2)
				(curved_edges yes)
				(filter_ratio 0.9)
				(enabled yes)
				(allow_two_segments yes)
				(prefer_zone_connections yes)
			)
		)
		(pad "15" smd oval
			(at 1.4 -0.905 270)
			(size 0.2 0.6)
			(layers "F.Cu" "F.Mask" "F.Paste")
			(net 576 "Net-(U19-MODE)")
			(pinfunction "MODE")
			(pintype "passive")
			(teardrops
				(best_length_ratio 0.2)
				(max_length 1)
				(best_width_ratio 0.9)
				(max_width 2)
				(curved_edges yes)
				(filter_ratio 0.9)
				(enabled yes)
				(allow_two_segments yes)
				(prefer_zone_connections yes)
			)
		)
		(pad "16" smd oval
			(at 0.9 -1.4 180)
			(size 0.2 0.6)
			(layers "F.Cu" "F.Mask" "F.Paste")
			(net 778 "unconnected-(U19-NC-Pad16)")
			(pinfunction "NC")
			(pintype "no_connect")
			(teardrops
				(best_length_ratio 0.2)
				(max_length 1)
				(best_width_ratio 0.9)
				(max_width 2)
				(curved_edges yes)
				(filter_ratio 0.9)
				(enabled yes)
				(allow_two_segments yes)
				(prefer_zone_connections yes)
			)
		)
		(pad "17" smd oval
			(at 0.45 -1.4 180)
			(size 0.2 0.6)
			(layers "F.Cu" "F.Mask" "F.Paste")
			(net 64 "Net-(U19-V_{CC})")
			(pinfunction "V_{CC}")
			(pintype "passive")
			(teardrops
				(best_length_ratio 0.2)
				(max_length 1)
				(best_width_ratio 0.9)
				(max_width 2)
				(curved_edges yes)
				(filter_ratio 0.9)
				(enabled yes)
				(allow_two_segments yes)
				(prefer_zone_connections yes)
			)
		)
		(pad "18" smd oval
			(at 0 -1.4 180)
			(size 0.2 0.6)
			(layers "F.Cu" "F.Mask" "F.Paste")
			(net 1 "GND")
			(pinfunction "PGND")
			(pintype "passive")
			(teardrops
				(best_length_ratio 0.2)
				(max_length 1)
				(best_width_ratio 0.9)
				(max_width 2)
				(curved_edges yes)
				(filter_ratio 0.9)
				(enabled yes)
				(allow_two_segments yes)
				(prefer_zone_connections yes)
			)
		)
		(pad "19" smd oval
			(at -0.455 -1.4 180)
			(size 0.2 0.6)
			(layers "F.Cu" "F.Mask" "F.Paste")
			(net 69 "Net-(C48-Pad2)")
			(pinfunction "SW")
			(pintype "passive")
			(teardrops
				(best_length_ratio 0.2)
				(max_length 1)
				(best_width_ratio 0.9)
				(max_width 2)
				(curved_edges yes)
				(filter_ratio 0.9)
				(enabled yes)
				(allow_two_segments yes)
				(prefer_zone_connections yes)
			)
		)
		(pad "20" smd oval
			(at -0.905 -1.4 180)
			(size 0.2 0.6)
			(layers "F.Cu" "F.Mask" "F.Paste")
			(net 69 "Net-(C48-Pad2)")
			(pinfunction "SW")
			(pintype "passive")
			(teardrops
				(best_length_ratio 0.2)
				(max_length 1)
				(best_width_ratio 0.9)
				(max_width 2)
				(curved_edges yes)
				(filter_ratio 0.9)
				(enabled yes)
				(allow_two_segments yes)
				(prefer_zone_connections yes)
			)
		)
		(pad "21" smd roundrect
			(at -0.06 0.018 180)
			(size 0.775 0.86)
			(layers "F.Cu" "F.Mask" "F.Paste")
			(roundrect_rratio 0.1)
			(net 1 "GND")
			(pinfunction "PGND")
			(pintype "passive")
			(solder_mask_margin -0.05)
			(solder_paste_margin -0.05)
			(teardrops
				(best_length_ratio 0.2)
				(max_length 1)
				(best_width_ratio 0.9)
				(max_width 2)
				(curved_edges yes)
				(filter_ratio 0.9)
				(enabled yes)
				(allow_two_segments yes)
				(prefer_zone_connections yes)
			)
		)
	)
	(footprint "antmicro-footprints:R_0402_1005Metric"
		(layer "F.Cu")
		(at 219.73 123.9 180)
		(descr "Resistor SMD 0402")
		(tags "resistor SMD 0402")
		(property "Reference" "R187"
			(at -3.62 -0.46 0)
			(layer "F.SilkS")
			(effects
				(font
					(size 0.7 0.7)
					(thickness 0.15)
				)
				(justify right bottom)
			)
		)
		(property "Value" "R_1k_0402"
			(at -1.011843 1.772047 0)
			(layer "F.Fab")
			(effects
				(font
					(size 0.7 0.7)
					(thickness 0.15)
				)
				(justify right bottom)
			)
		)
		(property "Datasheet" "https://www.bourns.com/docs/product-datasheets/cr.pdf"
			(at 0 0 180)
			(layer "F.Fab")
			(hide yes)
			(effects
				(font
					(size 1.27 1.27)
					(thickness 0.15)
				)
			)
		)
		(property "Author" "Antmicro"
			(at 439.46 247.8 0)
			(layer "F.Fab")
			(hide yes)
			(effects
				(font
					(size 1 1)
					(thickness 0.15)
				)
			)
		)
		(property "License" "Apache-2.0"
			(at 439.46 247.8 0)
			(layer "F.Fab")
			(hide yes)
			(effects
				(font
					(size 1 1)
					(thickness 0.15)
				)
			)
		)
		(property "MPN" "CR0402-FX-1001GLF"
			(at 439.46 247.8 0)
			(layer "F.Fab")
			(hide yes)
			(effects
				(font
					(size 1 1)
					(thickness 0.15)
				)
			)
		)
		(property "Manufacturer" "Bourns"
			(at 439.46 247.8 0)
			(layer "F.Fab")
			(hide yes)
			(effects
				(font
					(size 1 1)
					(thickness 0.15)
				)
			)
		)
		(property "Public" "False"
			(at 439.46 247.8 0)
			(layer "F.Fab")
			(hide yes)
			(effects
				(font
					(size 1 1)
					(thickness 0.15)
				)
			)
		)
		(property "Tolerance" "1%"
			(at 439.46 247.8 0)
			(layer "F.Fab")
			(hide yes)
			(effects
				(font
					(size 1 1)
					(thickness 0.15)
				)
			)
		)
		(property "Val" "1k"
			(at 439.46 247.8 0)
			(layer "F.Fab")
			(hide yes)
			(effects
				(font
					(size 1 1)
					(thickness 0.15)
				)
			)
		)
		(sheetname "PCIe misc")
		(sheetfile "pcie_misc.kicad_sch")
		(attr smd)
		(fp_rect
			(start -0.925 -0.47)
			(end 0.925 0.47)
			(stroke
				(width 0.05)
				(type default)
			)
			(fill no)
			(layer "F.CrtYd")
		)
		(fp_rect
			(start -0.5 -0.25)
			(end 0.5 0.25)
			(stroke
				(width 0.15)
				(type solid)
			)
			(fill no)
			(layer "F.Fab")
		)
		(pad "1" smd roundrect
			(at -0.48 0 180)
			(size 0.59 0.64)
			(layers "F.Cu" "F.Mask" "F.Paste")
			(roundrect_rratio 0.25)
			(net 2 "+3V3")
			(pintype "passive")
			(teardrops
				(best_length_ratio 0.2)
				(max_length 1)
				(best_width_ratio 0.9)
				(max_width 2)
				(curved_edges yes)
				(filter_ratio 0.9)
				(enabled yes)
				(allow_two_segments yes)
				(prefer_zone_connections yes)
			)
		)
		(pad "2" smd roundrect
			(at 0.48 0 180)
			(size 0.59 0.64)
			(layers "F.Cu" "F.Mask" "F.Paste")
			(roundrect_rratio 0.25)
			(net 607 "Net-(U37-~{HIBW_BYPM_LOBW})")
			(pintype "passive")
			(teardrops
				(best_length_ratio 0.2)
				(max_length 1)
				(best_width_ratio 0.9)
				(max_width 2)
				(curved_edges yes)
				(filter_ratio 0.9)
				(enabled yes)
				(allow_two_segments yes)
				(prefer_zone_connections yes)
			)
		)
	)
)
